(kicad_pcb
	(version 20260206)
	(generator "pcbnew")
	(generator_version "10.0")
	(general
		(thickness 1.6)
		(legacy_teardrops no)
	)
	(paper "A4")
	(title_block
		(title "01162023_DA0F0TEBIF0_F0T_Expander_BD_F_brd_V02_OCP.brd")
		(comment 1 "Grand Teton / footprints 1347-1352 of 9728")
	)
	(layers
		(0 "F.Cu" signal "TOP")
		(4 "In1.Cu" signal "GND")
		(6 "In2.Cu" signal "VCC")
		(8 "In3.Cu" signal "VCC1")
		(10 "In4.Cu" signal "GND1")
		(12 "In5.Cu" signal "IN1")
		(14 "In6.Cu" signal "GND2")
		(16 "In7.Cu" signal "IN2")
		(18 "In8.Cu" signal "GND3")
		(20 "In9.Cu" signal "IN3")
		(22 "In10.Cu" signal "GND4")
		(24 "In11.Cu" signal "IN4")
		(26 "In12.Cu" signal "GND5")
		(28 "In13.Cu" signal "IN5")
		(30 "In14.Cu" signal "GND6")
		(32 "In15.Cu" signal "IN6")
		(34 "In16.Cu" signal "GND7")
		(2 "B.Cu" signal "BOTTOM")
		(9 "F.Adhes" user "F.Adhesive")
		(11 "B.Adhes" user "B.Adhesive")
		(13 "F.Paste" user "Package Geometry/Pastemask Top")
		(15 "B.Paste" user "Package Geometry/Pastemask Bottom")
		(5 "F.SilkS" user "Ref Des/Silkscreen Top")
		(7 "B.SilkS" user "Ref Des/Silkscreen Bottom")
		(1 "F.Mask" user "Board Geometry/Soldermask Top")
		(3 "B.Mask" user "Board Geometry/Soldermask Bottom")
		(17 "Dwgs.User" user "User.Drawings")
		(19 "Cmts.User" user "User.Comments")
		(21 "Eco1.User" user "User.Eco1")
		(23 "Eco2.User" user "User.Eco2")
		(25 "Edge.Cuts" user "Board Geometry/Outline")
		(27 "Margin" user)
		(31 "F.CrtYd" user "Package Geometry/Place Bound Top")
		(29 "B.CrtYd" user "Package Geometry/Place Bound Bottom")
		(35 "F.Fab" user "Ref Des/Assembly Top")
		(33 "B.Fab" user "Ref Des/Assembly Bottom")
	)
	(footprint ""
		(layer "F.Cu")
		(at 152.634442 -252.356874 -90)
		(property "Reference" "R1295"
			(at 0 0 270)
			(layer "F.SilkS")
			(hide yes)
			(effects
				(font
					(size 1.27 1.27)
				)
			)
		)
		(property "Value" ""
			(at 0 0 270)
			(layer "F.Fab")
			(effects
				(font
					(size 1.27 1.27)
				)
			)
		)
		(duplicate_pad_numbers_are_jumpers no)
		(fp_line
			(start -0.7874 0.4064)
			(end -0.7874 -0.4064)
			(stroke
				(width 0.1524)
				(type default)
			)
			(layer "F.SilkS")
		)
		(fp_line
			(start 0.7874 0.4064)
			(end -0.7874 0.4064)
			(stroke
				(width 0.1524)
				(type default)
			)
			(layer "F.SilkS")
		)
		(fp_line
			(start -0.7874 -0.4064)
			(end 0.7874 -0.4064)
			(stroke
				(width 0.1524)
				(type default)
			)
			(layer "F.SilkS")
		)
		(fp_line
			(start 0.7874 -0.4064)
			(end 0.7874 0.4064)
			(stroke
				(width 0.1524)
				(type default)
			)
			(layer "F.SilkS")
		)
		(fp_line
			(start -0.67945 0.3048)
			(end -0.67945 -0.305054)
			(stroke
				(width 0.1)
				(type default)
			)
			(layer "F.Fab")
		)
		(fp_line
			(start -0.12065 0.3048)
			(end -0.67945 0.3048)
			(stroke
				(width 0.1)
				(type default)
			)
			(layer "F.Fab")
		)
		(fp_line
			(start 0.120396 0.3048)
			(end 0.120396 0.2794)
			(stroke
				(width 0.1)
				(type default)
			)
			(layer "F.Fab")
		)
		(fp_line
			(start 0.67945 0.3048)
			(end 0.120396 0.3048)
			(stroke
				(width 0.1)
				(type default)
			)
			(layer "F.Fab")
		)
		(fp_line
			(start -0.12065 0.2794)
			(end -0.12065 0.3048)
			(stroke
				(width 0.1)
				(type default)
			)
			(layer "F.Fab")
		)
		(fp_line
			(start 0.120396 0.2794)
			(end -0.12065 0.2794)
			(stroke
				(width 0.1)
				(type default)
			)
			(layer "F.Fab")
		)
		(fp_line
			(start -0.12065 -0.2794)
			(end 0.12065 -0.2794)
			(stroke
				(width 0.1)
				(type default)
			)
			(layer "F.Fab")
		)
		(fp_line
			(start 0.12065 -0.2794)
			(end 0.12065 -0.3048)
			(stroke
				(width 0.1)
				(type default)
			)
			(layer "F.Fab")
		)
		(fp_line
			(start 0.12065 -0.3048)
			(end 0.67945 -0.3048)
			(stroke
				(width 0.1)
				(type default)
			)
			(layer "F.Fab")
		)
		(fp_line
			(start 0.67945 -0.3048)
			(end 0.67945 0.3048)
			(stroke
				(width 0.1)
				(type default)
			)
			(layer "F.Fab")
		)
		(fp_line
			(start -0.67945 -0.305054)
			(end -0.12065 -0.305054)
			(stroke
				(width 0.1)
				(type default)
			)
			(layer "F.Fab")
		)
		(fp_line
			(start -0.12065 -0.305054)
			(end -0.12065 -0.2794)
			(stroke
				(width 0.1)
				(type default)
			)
			(layer "F.Fab")
		)
		(pad "1" smd circle
			(at -0.40005 0 270)
			(size 0 0)
			(layers "F.Cu" "F.Mask" "F.Paste")
			(net "GND")
		)
		(pad "2" smd circle
			(at 0.40005 0 270)
			(size 0 0)
			(layers "F.Cu" "F.Mask" "F.Paste")
			(net "PEX1_MODE_SEL6")
		)
	)
	(footprint ""
		(layer "F.Cu")
		(at 361.188 -190.246 180)
		(property "Reference" "R4642"
			(at 0 0 180)
			(layer "F.SilkS")
			(hide yes)
			(effects
				(font
					(size 1.27 1.27)
				)
			)
		)
		(property "Value" ""
			(at 0 0 180)
			(layer "F.Fab")
			(effects
				(font
					(size 1.27 1.27)
				)
			)
		)
		(duplicate_pad_numbers_are_jumpers no)
		(fp_line
			(start 0.7874 0.4064)
			(end -0.7874 0.4064)
			(stroke
				(width 0.1524)
				(type default)
			)
			(layer "F.SilkS")
		)
		(fp_line
			(start 0.7874 -0.4064)
			(end 0.7874 0.4064)
			(stroke
				(width 0.1524)
				(type default)
			)
			(layer "F.SilkS")
		)
		(fp_line
			(start -0.7874 0.4064)
			(end -0.7874 -0.4064)
			(stroke
				(width 0.1524)
				(type default)
			)
			(layer "F.SilkS")
		)
		(fp_line
			(start -0.7874 -0.4064)
			(end 0.7874 -0.4064)
			(stroke
				(width 0.1524)
				(type default)
			)
			(layer "F.SilkS")
		)
		(fp_line
			(start 0.67945 0.3048)
			(end 0.120396 0.3048)
			(stroke
				(width 0.1)
				(type default)
			)
			(layer "F.Fab")
		)
		(fp_line
			(start 0.67945 -0.3048)
			(end 0.67945 0.3048)
			(stroke
				(width 0.1)
				(type default)
			)
			(layer "F.Fab")
		)
		(fp_line
			(start 0.12065 -0.2794)
			(end 0.12065 -0.3048)
			(stroke
				(width 0.1)
				(type default)
			)
			(layer "F.Fab")
		)
		(fp_line
			(start 0.12065 -0.3048)
			(end 0.67945 -0.3048)
			(stroke
				(width 0.1)
				(type default)
			)
			(layer "F.Fab")
		)
		(fp_line
			(start 0.120396 0.3048)
			(end 0.120396 0.2794)
			(stroke
				(width 0.1)
				(type default)
			)
			(layer "F.Fab")
		)
		(fp_line
			(start 0.120396 0.2794)
			(end -0.12065 0.2794)
			(stroke
				(width 0.1)
				(type default)
			)
			(layer "F.Fab")
		)
		(fp_line
			(start -0.12065 0.3048)
			(end -0.67945 0.3048)
			(stroke
				(width 0.1)
				(type default)
			)
			(layer "F.Fab")
		)
		(fp_line
			(start -0.12065 0.2794)
			(end -0.12065 0.3048)
			(stroke
				(width 0.1)
				(type default)
			)
			(layer "F.Fab")
		)
		(fp_line
			(start -0.12065 -0.2794)
			(end 0.12065 -0.2794)
			(stroke
				(width 0.1)
				(type default)
			)
			(layer "F.Fab")
		)
		(fp_line
			(start -0.12065 -0.305054)
			(end -0.12065 -0.2794)
			(stroke
				(width 0.1)
				(type default)
			)
			(layer "F.Fab")
		)
		(fp_line
			(start -0.67945 0.3048)
			(end -0.67945 -0.305054)
			(stroke
				(width 0.1)
				(type default)
			)
			(layer "F.Fab")
		)
		(fp_line
			(start -0.67945 -0.305054)
			(end -0.12065 -0.305054)
			(stroke
				(width 0.1)
				(type default)
			)
			(layer "F.Fab")
		)
		(pad "1" smd circle
			(at -0.40005 0 180)
			(size 0 0)
			(layers "F.Cu" "F.Mask" "F.Paste")
			(net "PRSNT_SSD2_FPGA_PCA9555_N")
		)
		(pad "2" smd circle
			(at 0.40005 0 180)
			(size 0 0)
			(layers "F.Cu" "F.Mask" "F.Paste")
			(net "PRSNT_SSD2_FPGA_R_N")
		)
	)
	(footprint ""
		(layer "F.Cu")
		(at 52.243736 -45.88891)
		(property "Reference" "R519"
			(at 0 0 0)
			(layer "F.SilkS")
			(hide yes)
			(effects
				(font
					(size 1.27 1.27)
				)
			)
		)
		(property "Value" ""
			(at 0 0 0)
			(layer "F.Fab")
			(effects
				(font
					(size 1.27 1.27)
				)
			)
		)
		(duplicate_pad_numbers_are_jumpers no)
		(fp_line
			(start -0.7874 -0.4064)
			(end 0.7874 -0.4064)
			(stroke
				(width 0.1524)
				(type default)
			)
			(layer "F.SilkS")
		)
		(fp_line
			(start -0.7874 0.4064)
			(end -0.7874 -0.4064)
			(stroke
				(width 0.1524)
				(type default)
			)
			(layer "F.SilkS")
		)
		(fp_line
			(start 0.7874 -0.4064)
			(end 0.7874 0.4064)
			(stroke
				(width 0.1524)
				(type default)
			)
			(layer "F.SilkS")
		)
		(fp_line
			(start 0.7874 0.4064)
			(end -0.7874 0.4064)
			(stroke
				(width 0.1524)
				(type default)
			)
			(layer "F.SilkS")
		)
		(fp_line
			(start -0.67945 -0.305054)
			(end -0.12065 -0.305054)
			(stroke
				(width 0.1)
				(type default)
			)
			(layer "F.Fab")
		)
		(fp_line
			(start -0.67945 0.3048)
			(end -0.67945 -0.305054)
			(stroke
				(width 0.1)
				(type default)
			)
			(layer "F.Fab")
		)
		(fp_line
			(start -0.12065 -0.305054)
			(end -0.12065 -0.2794)
			(stroke
				(width 0.1)
				(type default)
			)
			(layer "F.Fab")
		)
		(fp_line
			(start -0.12065 -0.2794)
			(end 0.12065 -0.2794)
			(stroke
				(width 0.1)
				(type default)
			)
			(layer "F.Fab")
		)
		(fp_line
			(start -0.12065 0.2794)
			(end -0.12065 0.3048)
			(stroke
				(width 0.1)
				(type default)
			)
			(layer "F.Fab")
		)
		(fp_line
			(start -0.12065 0.3048)
			(end -0.67945 0.3048)
			(stroke
				(width 0.1)
				(type default)
			)
			(layer "F.Fab")
		)
		(fp_line
			(start 0.120396 0.2794)
			(end -0.12065 0.2794)
			(stroke
				(width 0.1)
				(type default)
			)
			(layer "F.Fab")
		)
		(fp_line
			(start 0.120396 0.3048)
			(end 0.120396 0.2794)
			(stroke
				(width 0.1)
				(type default)
			)
			(layer "F.Fab")
		)
		(fp_line
			(start 0.12065 -0.3048)
			(end 0.67945 -0.3048)
			(stroke
				(width 0.1)
				(type default)
			)
			(layer "F.Fab")
		)
		(fp_line
			(start 0.12065 -0.2794)
			(end 0.12065 -0.3048)
			(stroke
				(width 0.1)
				(type default)
			)
			(layer "F.Fab")
		)
		(fp_line
			(start 0.67945 -0.3048)
			(end 0.67945 0.3048)
			(stroke
				(width 0.1)
				(type default)
			)
			(layer "F.Fab")
		)
		(fp_line
			(start 0.67945 0.3048)
			(end 0.120396 0.3048)
			(stroke
				(width 0.1)
				(type default)
			)
			(layer "F.Fab")
		)
		(pad "1" smd circle
			(at -0.40005 0)
			(size 0 0)
			(layers "F.Cu" "F.Mask" "F.Paste")
			(net "SSD1_ADC_A0")
		)
		(pad "2" smd circle
			(at 0.40005 0)
			(size 0 0)
			(layers "F.Cu" "F.Mask" "F.Paste")
			(net "GND")
		)
	)
	(footprint ""
		(layer "F.Cu")
		(at 443.922658 -22.867366 90)
		(property "Reference" "C3979"
			(at 0 0 90)
			(layer "F.SilkS")
			(hide yes)
			(effects
				(font
					(size 1.27 1.27)
				)
			)
		)
		(property "Value" ""
			(at 0 0 90)
			(layer "F.Fab")
			(effects
				(font
					(size 1.27 1.27)
				)
			)
		)
		(duplicate_pad_numbers_are_jumpers no)
		(fp_line
			(start 0.7874 -0.4064)
			(end 0.7874 0.4064)
			(stroke
				(width 0.1524)
				(type default)
			)
			(layer "F.SilkS")
		)
		(fp_line
			(start -0.7874 -0.4064)
			(end 0.7874 -0.4064)
			(stroke
				(width 0.1524)
				(type default)
			)
			(layer "F.SilkS")
		)
		(fp_line
			(start 0.7874 0.4064)
			(end -0.7874 0.4064)
			(stroke
				(width 0.1524)
				(type default)
			)
			(layer "F.SilkS")
		)
		(fp_line
			(start -0.7874 0.4064)
			(end -0.7874 -0.4064)
			(stroke
				(width 0.1524)
				(type default)
			)
			(layer "F.SilkS")
		)
		(fp_line
			(start -0.12065 -0.305054)
			(end -0.12065 -0.2794)
			(stroke
				(width 0.1)
				(type default)
			)
			(layer "F.Fab")
		)
		(fp_line
			(start -0.67945 -0.305054)
			(end -0.12065 -0.305054)
			(stroke
				(width 0.1)
				(type default)
			)
			(layer "F.Fab")
		)
		(fp_line
			(start 0.67945 -0.3048)
			(end 0.67945 0.3048)
			(stroke
				(width 0.1)
				(type default)
			)
			(layer "F.Fab")
		)
		(fp_line
			(start 0.12065 -0.3048)
			(end 0.67945 -0.3048)
			(stroke
				(width 0.1)
				(type default)
			)
			(layer "F.Fab")
		)
		(fp_line
			(start 0.12065 -0.2794)
			(end 0.12065 -0.3048)
			(stroke
				(width 0.1)
				(type default)
			)
			(layer "F.Fab")
		)
		(fp_line
			(start -0.12065 -0.2794)
			(end 0.12065 -0.2794)
			(stroke
				(width 0.1)
				(type default)
			)
			(layer "F.Fab")
		)
		(fp_line
			(start 0.120396 0.2794)
			(end -0.12065 0.2794)
			(stroke
				(width 0.1)
				(type default)
			)
			(layer "F.Fab")
		)
		(fp_line
			(start -0.12065 0.2794)
			(end -0.12065 0.3048)
			(stroke
				(width 0.1)
				(type default)
			)
			(layer "F.Fab")
		)
		(fp_line
			(start 0.67945 0.3048)
			(end 0.120396 0.3048)
			(stroke
				(width 0.1)
				(type default)
			)
			(layer "F.Fab")
		)
		(fp_line
			(start 0.120396 0.3048)
			(end 0.120396 0.2794)
			(stroke
				(width 0.1)
				(type default)
			)
			(layer "F.Fab")
		)
		(fp_line
			(start -0.12065 0.3048)
			(end -0.67945 0.3048)
			(stroke
				(width 0.1)
				(type default)
			)
			(layer "F.Fab")
		)
		(fp_line
			(start -0.67945 0.3048)
			(end -0.67945 -0.305054)
			(stroke
				(width 0.1)
				(type default)
			)
			(layer "F.Fab")
		)
		(pad "1" smd circle
			(at -0.40005 0 90)
			(size 0 0)
			(layers "F.Cu" "F.Mask" "F.Paste")
			(net "P12V_SSD15")
		)
		(pad "2" smd circle
			(at 0.40005 0 90)
			(size 0 0)
			(layers "F.Cu" "F.Mask" "F.Paste")
			(net "GND")
		)
	)
	(footprint ""
		(layer "F.Cu")
		(at 86.120478 -26.666444 -90)
		(property "Reference" "R4059"
			(at 0 0 270)
			(layer "F.SilkS")
			(hide yes)
			(effects
				(font
					(size 1.27 1.27)
				)
			)
		)
		(property "Value" ""
			(at 0 0 270)
			(layer "F.Fab")
			(effects
				(font
					(size 1.27 1.27)
				)
			)
		)
		(duplicate_pad_numbers_are_jumpers no)
		(fp_line
			(start -0.7874 0.4064)
			(end -0.7874 -0.4064)
			(stroke
				(width 0.1524)
				(type default)
			)
			(layer "F.SilkS")
		)
		(fp_line
			(start 0.7874 0.4064)
			(end -0.7874 0.4064)
			(stroke
				(width 0.1524)
				(type default)
			)
			(layer "F.SilkS")
		)
		(fp_line
			(start -0.7874 -0.4064)
			(end 0.7874 -0.4064)
			(stroke
				(width 0.1524)
				(type default)
			)
			(layer "F.SilkS")
		)
		(fp_line
			(start 0.7874 -0.4064)
			(end 0.7874 0.4064)
			(stroke
				(width 0.1524)
				(type default)
			)
			(layer "F.SilkS")
		)
		(fp_line
			(start -0.67945 0.3048)
			(end -0.67945 -0.305054)
			(stroke
				(width 0.1)
				(type default)
			)
			(layer "F.Fab")
		)
		(fp_line
			(start -0.12065 0.3048)
			(end -0.67945 0.3048)
			(stroke
				(width 0.1)
				(type default)
			)
			(layer "F.Fab")
		)
		(fp_line
			(start 0.120396 0.3048)
			(end 0.120396 0.2794)
			(stroke
				(width 0.1)
				(type default)
			)
			(layer "F.Fab")
		)
		(fp_line
			(start 0.67945 0.3048)
			(end 0.120396 0.3048)
			(stroke
				(width 0.1)
				(type default)
			)
			(layer "F.Fab")
		)
		(fp_line
			(start -0.12065 0.2794)
			(end -0.12065 0.3048)
			(stroke
				(width 0.1)
				(type default)
			)
			(layer "F.Fab")
		)
		(fp_line
			(start 0.120396 0.2794)
			(end -0.12065 0.2794)
			(stroke
				(width 0.1)
				(type default)
			)
			(layer "F.Fab")
		)
		(fp_line
			(start -0.12065 -0.2794)
			(end 0.12065 -0.2794)
			(stroke
				(width 0.1)
				(type default)
			)
			(layer "F.Fab")
		)
		(fp_line
			(start 0.12065 -0.2794)
			(end 0.12065 -0.3048)
			(stroke
				(width 0.1)
				(type default)
			)
			(layer "F.Fab")
		)
		(fp_line
			(start 0.12065 -0.3048)
			(end 0.67945 -0.3048)
			(stroke
				(width 0.1)
				(type default)
			)
			(layer "F.Fab")
		)
		(fp_line
			(start 0.67945 -0.3048)
			(end 0.67945 0.3048)
			(stroke
				(width 0.1)
				(type default)
			)
			(layer "F.Fab")
		)
		(fp_line
			(start -0.67945 -0.305054)
			(end -0.12065 -0.305054)
			(stroke
				(width 0.1)
				(type default)
			)
			(layer "F.Fab")
		)
		(fp_line
			(start -0.12065 -0.305054)
			(end -0.12065 -0.2794)
			(stroke
				(width 0.1)
				(type default)
			)
			(layer "F.Fab")
		)
		(pad "1" smd circle
			(at -0.40005 0 270)
			(size 0 0)
			(layers "F.Cu" "F.Mask" "F.Paste")
			(net "PRSNT_SSD3_R_N")
		)
		(pad "2" smd circle
			(at 0.40005 0 270)
			(size 0 0)
			(layers "F.Cu" "F.Mask" "F.Paste")
			(net "PRSNT_SSD3_N")
		)
	)
	(footprint ""
		(layer "F.Cu")
		(at 236.018324 -202.760834)
		(property "Reference" "R4857"
			(at 0 0 0)
			(layer "F.SilkS")
			(hide yes)
			(effects
				(font
					(size 1.27 1.27)
				)
			)
		)
		(property "Value" ""
			(at 0 0 0)
			(layer "F.Fab")
			(effects
				(font
					(size 1.27 1.27)
				)
			)
		)
		(duplicate_pad_numbers_are_jumpers no)
		(fp_line
			(start -0.7874 -0.4064)
			(end 0.7874 -0.4064)
			(stroke
				(width 0.1524)
				(type default)
			)
			(layer "F.SilkS")
		)
		(fp_line
			(start -0.7874 0.4064)
			(end -0.7874 -0.4064)
			(stroke
				(width 0.1524)
				(type default)
			)
			(layer "F.SilkS")
		)
		(fp_line
			(start 0.7874 -0.4064)
			(end 0.7874 0.4064)
			(stroke
				(width 0.1524)
				(type default)
			)
			(layer "F.SilkS")
		)
		(fp_line
			(start 0.7874 0.4064)
			(end -0.7874 0.4064)
			(stroke
				(width 0.1524)
				(type default)
			)
			(layer "F.SilkS")
		)
		(fp_line
			(start -0.67945 -0.305054)
			(end -0.12065 -0.305054)
			(stroke
				(width 0.1)
				(type default)
			)
			(layer "F.Fab")
		)
		(fp_line
			(start -0.67945 0.3048)
			(end -0.67945 -0.305054)
			(stroke
				(width 0.1)
				(type default)
			)
			(layer "F.Fab")
		)
		(fp_line
			(start -0.12065 -0.305054)
			(end -0.12065 -0.2794)
			(stroke
				(width 0.1)
				(type default)
			)
			(layer "F.Fab")
		)
		(fp_line
			(start -0.12065 -0.2794)
			(end 0.12065 -0.2794)
			(stroke
				(width 0.1)
				(type default)
			)
			(layer "F.Fab")
		)
		(fp_line
			(start -0.12065 0.2794)
			(end -0.12065 0.3048)
			(stroke
				(width 0.1)
				(type default)
			)
			(layer "F.Fab")
		)
		(fp_line
			(start -0.12065 0.3048)
			(end -0.67945 0.3048)
			(stroke
				(width 0.1)
				(type default)
			)
			(layer "F.Fab")
		)
		(fp_line
			(start 0.120396 0.2794)
			(end -0.12065 0.2794)
			(stroke
				(width 0.1)
				(type default)
			)
			(layer "F.Fab")
		)
		(fp_line
			(start 0.120396 0.3048)
			(end 0.120396 0.2794)
			(stroke
				(width 0.1)
				(type default)
			)
			(layer "F.Fab")
		)
		(fp_line
			(start 0.12065 -0.3048)
			(end 0.67945 -0.3048)
			(stroke
				(width 0.1)
				(type default)
			)
			(layer "F.Fab")
		)
		(fp_line
			(start 0.12065 -0.2794)
			(end 0.12065 -0.3048)
			(stroke
				(width 0.1)
				(type default)
			)
			(layer "F.Fab")
		)
		(fp_line
			(start 0.67945 -0.3048)
			(end 0.67945 0.3048)
			(stroke
				(width 0.1)
				(type default)
			)
			(layer "F.Fab")
		)
		(fp_line
			(start 0.67945 0.3048)
			(end 0.120396 0.3048)
			(stroke
				(width 0.1)
				(type default)
			)
			(layer "F.Fab")
		)
		(pad "1" smd circle
			(at -0.40005 0)
			(size 0 0)
			(layers "F.Cu" "F.Mask" "F.Paste")
			(net "P3V3_LED")
		)
		(pad "2" smd circle
			(at 0.40005 0)
			(size 0 0)
			(layers "F.Cu" "F.Mask" "F.Paste")
			(net "BMC_HEARTBEAT_N_D")
		)
	)
)
